(kicad_pcb
	(version 20260206)
	(generator "pcbnew")
	(generator_version "10.0")
	(general
		(thickness 1.6)
		(legacy_teardrops no)
	)
	(paper "A4")
	(title_block
		(title "04192023_DAF0TMB3IC0_F0TG_MB_C_brd_V02_OCP.brd")
		(comment 1 "Grand Teton / footprint 2783 of 8354 (U26), pads 6001-6102 of 6102")
	)
	(layers
		(0 "F.Cu" signal "TOP")
		(4 "In1.Cu" signal "GND")
		(6 "In2.Cu" signal "IN1")
		(8 "In3.Cu" signal "GND1")
		(10 "In4.Cu" signal "IN2")
		(12 "In5.Cu" signal "GND2")
		(14 "In6.Cu" signal "IN3")
		(16 "In7.Cu" signal "GND3")
		(18 "In8.Cu" signal "VCC")
		(20 "In9.Cu" signal "VCC1")
		(22 "In10.Cu" signal "GND4")
		(24 "In11.Cu" signal "IN4")
		(26 "In12.Cu" signal "GND5")
		(28 "In13.Cu" signal "IN5")
		(30 "In14.Cu" signal "GND6")
		(32 "In15.Cu" signal "IN6")
		(34 "In16.Cu" signal "GND7")
		(2 "B.Cu" signal "BOTTOM")
		(9 "F.Adhes" user "F.Adhesive")
		(11 "B.Adhes" user "B.Adhesive")
		(13 "F.Paste" user "Package Geometry/Pastemask Top")
		(15 "B.Paste" user "Package Geometry/Pastemask Bottom")
		(5 "F.SilkS" user "Ref Des/Silkscreen Top")
		(7 "B.SilkS" user "Ref Des/Silkscreen Bottom")
		(1 "F.Mask" user "Board Geometry/Soldermask Top")
		(3 "B.Mask" user "Board Geometry/Soldermask Bottom")
		(17 "Dwgs.User" user "User.Drawings")
		(19 "Cmts.User" user "User.Comments")
		(21 "Eco1.User" user "User.Eco1")
		(23 "Eco2.User" user "User.Eco2")
		(25 "Edge.Cuts" user "Board Geometry/Outline")
		(27 "Margin" user)
		(31 "F.CrtYd" user "Package Geometry/Place Bound Top")
		(29 "B.CrtYd" user "Package Geometry/Place Bound Bottom")
		(35 "F.Fab" user "Ref Des/Assembly Top")
		(33 "B.Fab" user "Ref Des/Assembly Bottom")
	)
	(footprint ""
		(layer "F.Cu")
		(at 111.927894 -258.880356 180)
		(property "Reference" "U26"
			(at -45.05579 -61.794136 0)
			(unlocked yes)
			(layer "F.SilkS")
			(effects
				(font
					(size 0.7874 0.5842)
					(thickness 0.1524)
				)
			)
		)
		(property "Value" ""
			(at 0 0 180)
			(layer "F.Fab")
			(effects
				(font
					(size 1.27 1.27)
				)
			)
		)
		(duplicate_pad_numbers_are_jumpers no)
		(pad "W46" smd circle
			(at 7.199884 -22.23008 180)
			(size 0.450088 0.450088)
			(layers "F.Cu" "F.Mask" "F.Paste")
			(net "PVDDCR_CPU0_P1")
		)
		(pad "W47" smd circle
			(at 8.139938 -22.23008 180)
			(size 0.450088 0.450088)
			(layers "F.Cu" "F.Mask" "F.Paste")
			(net "PVDDCR_CPU0_P1")
		)
		(pad "W48" smd circle
			(at 9.079992 -22.23008 180)
			(size 0.450088 0.450088)
			(layers "F.Cu" "F.Mask" "F.Paste")
			(net "GND")
		)
		(pad "W49" smd circle
			(at 10.020046 -22.23008 180)
			(size 0.450088 0.450088)
			(layers "F.Cu" "F.Mask" "F.Paste")
			(net "P5E_CPU1_G1_RX_DN<9>")
		)
		(pad "W50" smd circle
			(at 10.9601 -22.23008 180)
			(size 0.450088 0.450088)
			(layers "F.Cu" "F.Mask" "F.Paste")
			(net "P5E_CPU1_G1_RX_DP<9>")
		)
		(pad "W51" smd circle
			(at 11.8999 -22.23008 180)
			(size 0.450088 0.450088)
			(layers "F.Cu" "F.Mask" "F.Paste")
			(net "GND")
		)
		(pad "W52" smd circle
			(at 12.839954 -22.23008 180)
			(size 0.450088 0.450088)
			(layers "F.Cu" "F.Mask" "F.Paste")
			(net "P5E_CPU1_G1_RX_DN<13>")
		)
		(pad "W53" smd circle
			(at 13.780008 -22.23008 180)
			(size 0.450088 0.450088)
			(layers "F.Cu" "F.Mask" "F.Paste")
			(net "P5E_CPU1_G1_RX_DP<13>")
		)
		(pad "W54" smd circle
			(at 14.720062 -22.23008 180)
			(size 0.450088 0.450088)
			(layers "F.Cu" "F.Mask" "F.Paste")
			(net "GND")
		)
		(pad "W55" smd circle
			(at 15.660116 -22.23008 180)
			(size 0.450088 0.450088)
			(layers "F.Cu" "F.Mask" "F.Paste")
			(net "M_C_CPU1_SA_DQ<19>")
		)
		(pad "W56" smd circle
			(at 16.599916 -22.23008 180)
			(size 0.450088 0.450088)
			(layers "F.Cu" "F.Mask" "F.Paste")
			(net "GND")
		)
		(pad "W57" smd circle
			(at 17.53997 -22.23008 180)
			(size 0.450088 0.450088)
			(layers "F.Cu" "F.Mask" "F.Paste")
			(net "M_C_CPU1_SA_DQS_DP<2>")
		)
		(pad "W58" smd circle
			(at 18.480024 -22.23008 180)
			(size 0.450088 0.450088)
			(layers "F.Cu" "F.Mask" "F.Paste")
			(net "GND")
		)
		(pad "W59" smd circle
			(at 19.420078 -22.23008 180)
			(size 0.450088 0.450088)
			(layers "F.Cu" "F.Mask" "F.Paste")
			(net "M_D_CPU1_SA_DQ<19>")
		)
		(pad "W60" smd circle
			(at 20.359878 -22.23008 180)
			(size 0.450088 0.450088)
			(layers "F.Cu" "F.Mask" "F.Paste")
			(net "M_D_CPU1_SA_DQS_DP<2>")
		)
		(pad "W61" smd circle
			(at 21.299932 -22.23008 180)
			(size 0.450088 0.450088)
			(layers "F.Cu" "F.Mask" "F.Paste")
			(net "GND")
		)
		(pad "W62" smd circle
			(at 22.239986 -22.23008 180)
			(size 0.450088 0.450088)
			(layers "F.Cu" "F.Mask" "F.Paste")
			(net "M_B_CPU1_SA_DQ<19>")
		)
		(pad "W63" smd circle
			(at 23.18004 -22.23008 180)
			(size 0.450088 0.450088)
			(layers "F.Cu" "F.Mask" "F.Paste")
			(net "GND")
		)
		(pad "W64" smd circle
			(at 24.120094 -22.23008 180)
			(size 0.450088 0.450088)
			(layers "F.Cu" "F.Mask" "F.Paste")
			(net "M_B_CPU1_SA_DQS_DP<2>")
		)
		(pad "W65" smd circle
			(at 25.059894 -22.23008 180)
			(size 0.450088 0.450088)
			(layers "F.Cu" "F.Mask" "F.Paste")
			(net "GND")
		)
		(pad "W66" smd circle
			(at 25.999948 -22.23008 180)
			(size 0.450088 0.450088)
			(layers "F.Cu" "F.Mask" "F.Paste")
			(net "M_F_CPU1_SA_DQ<19>")
		)
		(pad "W67" smd circle
			(at 26.940002 -22.23008 180)
			(size 0.450088 0.450088)
			(layers "F.Cu" "F.Mask" "F.Paste")
			(net "M_F_CPU1_SA_DQS_DP<2>")
		)
		(pad "W68" smd circle
			(at 27.880056 -22.23008 180)
			(size 0.450088 0.450088)
			(layers "F.Cu" "F.Mask" "F.Paste")
			(net "GND")
		)
		(pad "W69" smd circle
			(at 28.82011 -22.23008 180)
			(size 0.450088 0.450088)
			(layers "F.Cu" "F.Mask" "F.Paste")
			(net "M_E_CPU1_SA_DQ<19>")
		)
		(pad "W70" smd circle
			(at 29.75991 -22.23008 180)
			(size 0.450088 0.450088)
			(layers "F.Cu" "F.Mask" "F.Paste")
			(net "GND")
		)
		(pad "W71" smd circle
			(at 30.699964 -22.23008 180)
			(size 0.450088 0.450088)
			(layers "F.Cu" "F.Mask" "F.Paste")
			(net "M_E_CPU1_SA_DQS_DP<2>")
		)
		(pad "W72" smd circle
			(at 31.640018 -22.23008 180)
			(size 0.450088 0.450088)
			(layers "F.Cu" "F.Mask" "F.Paste")
			(net "GND")
		)
		(pad "W73" smd circle
			(at 32.580072 -22.23008 180)
			(size 0.450088 0.450088)
			(layers "F.Cu" "F.Mask" "F.Paste")
			(net "M_A_CPU1_SA_DQ<19>")
		)
		(pad "W74" smd circle
			(at 33.519872 -22.23008 180)
			(size 0.450088 0.450088)
			(layers "F.Cu" "F.Mask" "F.Paste")
			(net "M_A_CPU1_SA_DQS_DP<2>")
		)
		(pad "W75" smd circle
			(at 34.459926 -22.23008 180)
			(size 0.450088 0.450088)
			(layers "F.Cu" "F.Mask" "F.Paste")
			(net "GND")
		)
		(pad "Y2" smd circle
			(at -33.690052 -21.420074 180)
			(size 0.450088 0.450088)
			(layers "F.Cu" "F.Mask" "F.Paste")
			(net "M_G_CPU1_SA_DQS_DN<2>")
		)
		(pad "Y3" smd circle
			(at -32.749998 -21.420074 180)
			(size 0.450088 0.450088)
			(layers "F.Cu" "F.Mask" "F.Paste")
			(net "GND")
		)
		(pad "Y4" smd circle
			(at -31.809944 -21.420074 180)
			(size 0.450088 0.450088)
			(layers "F.Cu" "F.Mask" "F.Paste")
			(net "M_G_CPU1_SA_DQS_DN<7>")
		)
		(pad "Y5" smd circle
			(at -30.86989 -21.420074 180)
			(size 0.450088 0.450088)
			(layers "F.Cu" "F.Mask" "F.Paste")
			(net "PVDDCR_SOC_P1")
		)
		(pad "Y6" smd circle
			(at -29.93009 -21.420074 180)
			(size 0.450088 0.450088)
			(layers "F.Cu" "F.Mask" "F.Paste")
			(net "M_K_CPU1_SA_DQS_DN<2>")
		)
		(pad "Y7" smd circle
			(at -28.990036 -21.420074 180)
			(size 0.450088 0.450088)
			(layers "F.Cu" "F.Mask" "F.Paste")
			(net "M_K_CPU1_SA_DQS_DN<7>")
		)
		(pad "Y8" smd circle
			(at -28.049982 -21.420074 180)
			(size 0.450088 0.450088)
			(layers "F.Cu" "F.Mask" "F.Paste")
			(net "GND")
		)
		(pad "Y9" smd circle
			(at -27.109928 -21.420074 180)
			(size 0.450088 0.450088)
			(layers "F.Cu" "F.Mask" "F.Paste")
			(net "M_L_CPU1_SA_DQS_DN<2>")
		)
		(pad "Y10" smd circle
			(at -26.170128 -21.420074 180)
			(size 0.450088 0.450088)
			(layers "F.Cu" "F.Mask" "F.Paste")
			(net "GND")
		)
		(pad "Y11" smd circle
			(at -25.230074 -21.420074 180)
			(size 0.450088 0.450088)
			(layers "F.Cu" "F.Mask" "F.Paste")
			(net "M_L_CPU1_SA_DQS_DN<7>")
		)
		(pad "Y12" smd circle
			(at -24.29002 -21.420074 180)
			(size 0.450088 0.450088)
			(layers "F.Cu" "F.Mask" "F.Paste")
			(net "PVDDCR_SOC_P1")
		)
		(pad "Y13" smd circle
			(at -23.349966 -21.420074 180)
			(size 0.450088 0.450088)
			(layers "F.Cu" "F.Mask" "F.Paste")
			(net "M_H_CPU1_SA_DQS_DN<2>")
		)
		(pad "Y14" smd circle
			(at -22.409912 -21.420074 180)
			(size 0.450088 0.450088)
			(layers "F.Cu" "F.Mask" "F.Paste")
			(net "M_H_CPU1_SA_DQS_DN<7>")
		)
		(pad "Y15" smd circle
			(at -21.470112 -21.420074 180)
			(size 0.450088 0.450088)
			(layers "F.Cu" "F.Mask" "F.Paste")
			(net "GND")
		)
		(pad "Y16" smd circle
			(at -20.530058 -21.420074 180)
			(size 0.450088 0.450088)
			(layers "F.Cu" "F.Mask" "F.Paste")
			(net "M_J_CPU1_SA_DQS_DN<2>")
		)
		(pad "Y17" smd circle
			(at -19.590004 -21.420074 180)
			(size 0.450088 0.450088)
			(layers "F.Cu" "F.Mask" "F.Paste")
			(net "GND")
		)
		(pad "Y18" smd circle
			(at -18.64995 -21.420074 180)
			(size 0.450088 0.450088)
			(layers "F.Cu" "F.Mask" "F.Paste")
			(net "M_J_CPU1_SA_DQS_DN<7>")
		)
		(pad "Y19" smd circle
			(at -17.709896 -21.420074 180)
			(size 0.450088 0.450088)
			(layers "F.Cu" "F.Mask" "F.Paste")
			(net "PVDDCR_SOC_P1")
		)
		(pad "Y20" smd circle
			(at -16.770096 -21.420074 180)
			(size 0.450088 0.450088)
			(layers "F.Cu" "F.Mask" "F.Paste")
			(net "M_I_CPU1_SA_DQS_DN<2>")
		)
		(pad "Y21" smd circle
			(at -15.830042 -21.420074 180)
			(size 0.450088 0.450088)
			(layers "F.Cu" "F.Mask" "F.Paste")
			(net "M_I_CPU1_SA_DQS_DN<7>")
		)
		(pad "Y22" smd circle
			(at -14.889988 -21.420074 180)
			(size 0.450088 0.450088)
			(layers "F.Cu" "F.Mask" "F.Paste")
			(net "GND")
		)
		(pad "Y23" smd circle
			(at -13.949934 -21.420074 180)
			(size 0.450088 0.450088)
			(layers "F.Cu" "F.Mask" "F.Paste")
			(net "GND")
		)
		(pad "Y24" smd circle
			(at -13.00988 -21.420074 180)
			(size 0.450088 0.450088)
			(layers "F.Cu" "F.Mask" "F.Paste")
			(net "GND")
		)
		(pad "Y25" smd circle
			(at -12.07008 -21.420074 180)
			(size 0.450088 0.450088)
			(layers "F.Cu" "F.Mask" "F.Paste")
			(net "GND")
		)
		(pad "Y26" smd circle
			(at -11.130026 -21.420074 180)
			(size 0.450088 0.450088)
			(layers "F.Cu" "F.Mask" "F.Paste")
			(net "GND")
		)
		(pad "Y27" smd circle
			(at -10.189972 -21.420074 180)
			(size 0.450088 0.450088)
			(layers "F.Cu" "F.Mask" "F.Paste")
			(net "GND")
		)
		(pad "Y28" smd circle
			(at -9.249918 -21.420074 180)
			(size 0.450088 0.450088)
			(layers "F.Cu" "F.Mask" "F.Paste")
			(net "GND")
		)
		(pad "Y29" smd circle
			(at -8.310118 -21.420074 180)
			(size 0.450088 0.450088)
			(layers "F.Cu" "F.Mask" "F.Paste")
			(net "TP_CPU1_TEST5_CCD11")
		)
		(pad "Y30" smd circle
			(at -7.370064 -21.420074 180)
			(size 0.450088 0.450088)
			(layers "F.Cu" "F.Mask" "F.Paste")
			(net "TP_CPU1_TEST5_CCD3")
		)
		(pad "Y31" smd circle
			(at -6.43001 -21.420074 180)
			(size 0.450088 0.450088)
			(layers "F.Cu" "F.Mask" "F.Paste")
			(net "GND")
		)
		(pad "Y32" smd circle
			(at -5.489956 -21.420074 180)
			(size 0.450088 0.450088)
			(layers "F.Cu" "F.Mask" "F.Paste")
			(net "GND")
		)
		(pad "Y33" smd circle
			(at -4.549902 -21.420074 180)
			(size 0.450088 0.450088)
			(layers "F.Cu" "F.Mask" "F.Paste")
			(net "GND")
		)
		(pad "Y34" smd circle
			(at -3.610102 -21.420074 180)
			(size 0.450088 0.450088)
			(layers "F.Cu" "F.Mask" "F.Paste")
			(net "GND")
		)
		(pad "Y35" smd circle
			(at -2.670048 -21.420074 180)
			(size 0.450088 0.450088)
			(layers "F.Cu" "F.Mask" "F.Paste")
			(net "PVDDCR_CPU0_P1")
		)
		(pad "Y36" smd circle
			(at -1.729994 -21.420074 180)
			(size 0.450088 0.450088)
			(layers "F.Cu" "F.Mask" "F.Paste")
			(net "PVDDCR_CPU0_P1")
		)
		(pad "Y37" smd circle
			(at -0.78994 -21.420074 180)
			(size 0.450088 0.450088)
			(layers "F.Cu" "F.Mask" "F.Paste")
			(net "GND")
		)
		(pad "Y39" smd circle
			(at 1.089914 -21.420074 180)
			(size 0.450088 0.450088)
			(layers "F.Cu" "F.Mask" "F.Paste")
			(net "GND")
		)
		(pad "Y40" smd circle
			(at 2.029968 -21.420074 180)
			(size 0.450088 0.450088)
			(layers "F.Cu" "F.Mask" "F.Paste")
			(net "PVDDCR_CPU0_P1")
		)
		(pad "Y41" smd circle
			(at 2.970022 -21.420074 180)
			(size 0.450088 0.450088)
			(layers "F.Cu" "F.Mask" "F.Paste")
			(net "PVDDCR_CPU0_P1")
		)
		(pad "Y42" smd circle
			(at 3.910076 -21.420074 180)
			(size 0.450088 0.450088)
			(layers "F.Cu" "F.Mask" "F.Paste")
			(net "GND")
		)
		(pad "Y43" smd circle
			(at 4.849876 -21.420074 180)
			(size 0.450088 0.450088)
			(layers "F.Cu" "F.Mask" "F.Paste")
			(net "GND")
		)
		(pad "Y44" smd circle
			(at 5.78993 -21.420074 180)
			(size 0.450088 0.450088)
			(layers "F.Cu" "F.Mask" "F.Paste")
			(net "GND")
		)
		(pad "Y45" smd circle
			(at 6.729984 -21.420074 180)
			(size 0.450088 0.450088)
			(layers "F.Cu" "F.Mask" "F.Paste")
			(net "GND")
		)
		(pad "Y46" smd circle
			(at 7.670038 -21.420074 180)
			(size 0.450088 0.450088)
			(layers "F.Cu" "F.Mask" "F.Paste")
			(net "TP_CPU1_TEST6_CCD3")
		)
		(pad "Y47" smd circle
			(at 8.610092 -21.420074 180)
			(size 0.450088 0.450088)
			(layers "F.Cu" "F.Mask" "F.Paste")
			(net "TP_CPU1_TEST5_CCD8")
		)
		(pad "Y48" smd circle
			(at 9.549892 -21.420074 180)
			(size 0.450088 0.450088)
			(layers "F.Cu" "F.Mask" "F.Paste")
			(net "GND")
		)
		(pad "Y49" smd circle
			(at 10.489946 -21.420074 180)
			(size 0.450088 0.450088)
			(layers "F.Cu" "F.Mask" "F.Paste")
			(net "GND")
		)
		(pad "Y50" smd circle
			(at 11.43 -21.420074 180)
			(size 0.450088 0.450088)
			(layers "F.Cu" "F.Mask" "F.Paste")
			(net "GND")
		)
		(pad "Y51" smd circle
			(at 12.370054 -21.420074 180)
			(size 0.450088 0.450088)
			(layers "F.Cu" "F.Mask" "F.Paste")
			(net "GND")
		)
		(pad "Y52" smd circle
			(at 13.310108 -21.420074 180)
			(size 0.450088 0.450088)
			(layers "F.Cu" "F.Mask" "F.Paste")
			(net "GND")
		)
		(pad "Y53" smd circle
			(at 14.249908 -21.420074 180)
			(size 0.450088 0.450088)
			(layers "F.Cu" "F.Mask" "F.Paste")
			(net "GND")
		)
		(pad "Y54" smd circle
			(at 15.189962 -21.420074 180)
			(size 0.450088 0.450088)
			(layers "F.Cu" "F.Mask" "F.Paste")
			(net "GND")
		)
		(pad "Y55" smd circle
			(at 16.130016 -21.420074 180)
			(size 0.450088 0.450088)
			(layers "F.Cu" "F.Mask" "F.Paste")
			(net "M_C_CPU1_SA_DQS_DN<7>")
		)
		(pad "Y56" smd circle
			(at 17.07007 -21.420074 180)
			(size 0.450088 0.450088)
			(layers "F.Cu" "F.Mask" "F.Paste")
			(net "M_C_CPU1_SA_DQS_DN<2>")
		)
		(pad "Y57" smd circle
			(at 18.010124 -21.420074 180)
			(size 0.450088 0.450088)
			(layers "F.Cu" "F.Mask" "F.Paste")
			(net "PVDDIO_P1")
		)
		(pad "Y58" smd circle
			(at 18.949924 -21.420074 180)
			(size 0.450088 0.450088)
			(layers "F.Cu" "F.Mask" "F.Paste")
			(net "M_D_CPU1_SA_DQS_DN<7>")
		)
		(pad "Y59" smd circle
			(at 19.889978 -21.420074 180)
			(size 0.450088 0.450088)
			(layers "F.Cu" "F.Mask" "F.Paste")
			(net "GND")
		)
		(pad "Y60" smd circle
			(at 20.830032 -21.420074 180)
			(size 0.450088 0.450088)
			(layers "F.Cu" "F.Mask" "F.Paste")
			(net "M_D_CPU1_SA_DQS_DN<2>")
		)
		(pad "Y61" smd circle
			(at 21.770086 -21.420074 180)
			(size 0.450088 0.450088)
			(layers "F.Cu" "F.Mask" "F.Paste")
			(net "GND")
		)
		(pad "Y62" smd circle
			(at 22.709886 -21.420074 180)
			(size 0.450088 0.450088)
			(layers "F.Cu" "F.Mask" "F.Paste")
			(net "M_B_CPU1_SA_DQS_DN<7>")
		)
		(pad "Y63" smd circle
			(at 23.64994 -21.420074 180)
			(size 0.450088 0.450088)
			(layers "F.Cu" "F.Mask" "F.Paste")
			(net "M_B_CPU1_SA_DQS_DN<2>")
		)
		(pad "Y64" smd circle
			(at 24.589994 -21.420074 180)
			(size 0.450088 0.450088)
			(layers "F.Cu" "F.Mask" "F.Paste")
			(net "PVDDIO_P1")
		)
		(pad "Y65" smd circle
			(at 25.530048 -21.420074 180)
			(size 0.450088 0.450088)
			(layers "F.Cu" "F.Mask" "F.Paste")
			(net "M_F_CPU1_SA_DQS_DN<7>")
		)
		(pad "Y66" smd circle
			(at 26.470102 -21.420074 180)
			(size 0.450088 0.450088)
			(layers "F.Cu" "F.Mask" "F.Paste")
			(net "GND")
		)
		(pad "Y67" smd circle
			(at 27.409902 -21.420074 180)
			(size 0.450088 0.450088)
			(layers "F.Cu" "F.Mask" "F.Paste")
			(net "M_F_CPU1_SA_DQS_DN<2>")
		)
		(pad "Y68" smd circle
			(at 28.349956 -21.420074 180)
			(size 0.450088 0.450088)
			(layers "F.Cu" "F.Mask" "F.Paste")
			(net "GND")
		)
		(pad "Y69" smd circle
			(at 29.29001 -21.420074 180)
			(size 0.450088 0.450088)
			(layers "F.Cu" "F.Mask" "F.Paste")
			(net "M_E_CPU1_SA_DQS_DN<7>")
		)
		(pad "Y70" smd circle
			(at 30.230064 -21.420074 180)
			(size 0.450088 0.450088)
			(layers "F.Cu" "F.Mask" "F.Paste")
			(net "M_E_CPU1_SA_DQS_DN<2>")
		)
		(pad "Y71" smd circle
			(at 31.170118 -21.420074 180)
			(size 0.450088 0.450088)
			(layers "F.Cu" "F.Mask" "F.Paste")
			(net "PVDDIO_P1")
		)
		(pad "Y72" smd circle
			(at 32.109918 -21.420074 180)
			(size 0.450088 0.450088)
			(layers "F.Cu" "F.Mask" "F.Paste")
			(net "M_A_CPU1_SA_DQS_DN<7>")
		)
		(pad "Y73" smd circle
			(at 33.049972 -21.420074 180)
			(size 0.450088 0.450088)
			(layers "F.Cu" "F.Mask" "F.Paste")
			(net "GND")
		)
		(pad "Y74" smd circle
			(at 33.990026 -21.420074 180)
			(size 0.450088 0.450088)
			(layers "F.Cu" "F.Mask" "F.Paste")
			(net "M_A_CPU1_SA_DQS_DN<2>")
		)
	)
)
